# T6G (Grand Teton) — schematic netlist excerpt (pin names and nets, part order shuffled) for the footprints in the layout excerpt that follows; sources: Cadence DE-HDL packaged netlist, KiCad conversion of 04192023_DAF0TMB3IC0_F0TG_MB_C_brd_V02_OCP.brd

PC611_3  Q_CAP  22UF 16V 20% X6S  pkg C0805  page 199 : A = SW_P12V_AUX_PVDDCR_SOC_P0_FLT ; B = GND
R1223  Q_RES  18K 1% CHIP  pkg 0402LF  page 258 : A = P1V8_CPU1_RT_1D_ADC ; B = GND
C2160  Q_CAP  22UF 4V 20% X6S  pkg C0402  page 68 : A = PVDD11_S3_P0 ; B = GND

(kicad_pcb
	(version 20260206)
	(generator "pcbnew")
	(generator_version "10.0")
	(general
		(thickness 1.6)
		(legacy_teardrops no)
	)
	(paper "A4")
	(title_block
		(title "04192023_DAF0TMB3IC0_F0TG_MB_C_brd_V02_OCP.brd")
		(comment 1 "Grand Teton / footprints 8032-8034 of 8354")
	)
	(layers
		(0 "F.Cu" signal "TOP")
		(4 "In1.Cu" signal "GND")
		(6 "In2.Cu" signal "IN1")
		(8 "In3.Cu" signal "GND1")
		(10 "In4.Cu" signal "IN2")
		(12 "In5.Cu" signal "GND2")
		(14 "In6.Cu" signal "IN3")
		(16 "In7.Cu" signal "GND3")
		(18 "In8.Cu" signal "VCC")
		(20 "In9.Cu" signal "VCC1")
		(22 "In10.Cu" signal "GND4")
		(24 "In11.Cu" signal "IN4")
		(26 "In12.Cu" signal "GND5")
		(28 "In13.Cu" signal "IN5")
		(30 "In14.Cu" signal "GND6")
		(32 "In15.Cu" signal "IN6")
		(34 "In16.Cu" signal "GND7")
		(2 "B.Cu" signal "BOTTOM")
		(9 "F.Adhes" user "F.Adhesive")
		(11 "B.Adhes" user "B.Adhesive")
		(13 "F.Paste" user "Package Geometry/Pastemask Top")
		(15 "B.Paste" user "Package Geometry/Pastemask Bottom")
		(5 "F.SilkS" user "Ref Des/Silkscreen Top")
		(7 "B.SilkS" user "Ref Des/Silkscreen Bottom")
		(1 "F.Mask" user "Board Geometry/Soldermask Top")
		(3 "B.Mask" user "Board Geometry/Soldermask Bottom")
		(17 "Dwgs.User" user "User.Drawings")
		(19 "Cmts.User" user "User.Comments")
		(21 "Eco1.User" user "User.Eco1")
		(23 "Eco2.User" user "User.Eco2")
		(25 "Edge.Cuts" user "Board Geometry/Outline")
		(27 "Margin" user)
		(31 "F.CrtYd" user "Package Geometry/Place Bound Top")
		(29 "B.CrtYd" user "Package Geometry/Place Bound Bottom")
		(35 "F.Fab" user "Ref Des/Assembly Top")
		(33 "B.Fab" user "Ref Des/Assembly Bottom")
	)
	(footprint ""
		(layer "B.Cu")
		(at 413.304736 -159.989012 90)
		(property "Reference" "PC611_3"
			(at 0 0 90)
			(layer "B.SilkS")
			(hide yes)
			(effects
				(font
					(size 1.27 1.27)
				)
				(justify mirror)
			)
		)
		(property "Value" ""
			(at 0 0 90)
			(layer "B.Fab")
			(effects
				(font
					(size 1.27 1.27)
				)
				(justify mirror)
			)
		)
		(duplicate_pad_numbers_are_jumpers no)
		(fp_line
			(start 1.524 -0.762)
			(end -1.524 -0.762)
			(stroke
				(width 0.1524)
				(type default)
			)
			(layer "B.SilkS")
		)
		(fp_line
			(start -1.524 -0.762)
			(end -1.524 0.762)
			(stroke
				(width 0.1524)
				(type default)
			)
			(layer "B.SilkS")
		)
		(fp_line
			(start 1.524 0.762)
			(end 1.524 -0.762)
			(stroke
				(width 0.1524)
				(type default)
			)
			(layer "B.SilkS")
		)
		(fp_line
			(start -1.524 0.762)
			(end 1.524 0.762)
			(stroke
				(width 0.1524)
				(type default)
			)
			(layer "B.SilkS")
		)
		(fp_line
			(start 1.1049 -0.724916)
			(end 1.1049 0.724916)
			(stroke
				(width 0.1)
				(type default)
			)
			(layer "B.Fab")
		)
		(fp_line
			(start -1.1049 -0.724916)
			(end 1.1049 -0.724916)
			(stroke
				(width 0.1)
				(type default)
			)
			(layer "B.Fab")
		)
		(fp_line
			(start 1.1049 0.724916)
			(end -1.1049 0.724916)
			(stroke
				(width 0.1)
				(type default)
			)
			(layer "B.Fab")
		)
		(fp_line
			(start -1.1049 0.724916)
			(end -1.1049 -0.724916)
			(stroke
				(width 0.1)
				(type default)
			)
			(layer "B.Fab")
		)
		(pad "1" smd rect
			(at 0.889 0 90)
			(size 1.016 1.27)
			(layers "B.Cu" "B.Mask" "B.Paste")
			(net "SW_P12V_AUX_PVDDCR_SOC_P0_FLT")
		)
		(pad "2" smd rect
			(at -0.889 0 90)
			(size 1.016 1.27)
			(layers "B.Cu" "B.Mask" "B.Paste")
			(net "GND")
		)
	)
	(footprint ""
		(layer "B.Cu")
		(at 234.80522 -325.894192 180)
		(property "Reference" "R1223"
			(at 0 0 0)
			(layer "B.SilkS")
			(hide yes)
			(effects
				(font
					(size 1.27 1.27)
				)
				(justify mirror)
			)
		)
		(property "Value" ""
			(at 0 0 0)
			(layer "B.Fab")
			(effects
				(font
					(size 1.27 1.27)
				)
				(justify mirror)
			)
		)
		(duplicate_pad_numbers_are_jumpers no)
		(fp_line
			(start 0.7874 0.4064)
			(end 0.7874 -0.4064)
			(stroke
				(width 0.1524)
				(type default)
			)
			(layer "B.SilkS")
		)
		(fp_line
			(start 0.7874 -0.4064)
			(end -0.7874 -0.4064)
			(stroke
				(width 0.1524)
				(type default)
			)
			(layer "B.SilkS")
		)
		(fp_line
			(start -0.7874 0.4064)
			(end 0.7874 0.4064)
			(stroke
				(width 0.1524)
				(type default)
			)
			(layer "B.SilkS")
		)
		(fp_line
			(start -0.7874 -0.4064)
			(end -0.7874 0.4064)
			(stroke
				(width 0.1524)
				(type default)
			)
			(layer "B.SilkS")
		)
		(fp_line
			(start 0.67945 0.3048)
			(end 0.67945 -0.305054)
			(stroke
				(width 0.1)
				(type default)
			)
			(layer "B.Fab")
		)
		(fp_line
			(start 0.67945 -0.305054)
			(end 0.12065 -0.305054)
			(stroke
				(width 0.1)
				(type default)
			)
			(layer "B.Fab")
		)
		(fp_line
			(start 0.12065 0.3048)
			(end 0.67945 0.3048)
			(stroke
				(width 0.1)
				(type default)
			)
			(layer "B.Fab")
		)
		(fp_line
			(start 0.12065 0.2794)
			(end 0.12065 0.3048)
			(stroke
				(width 0.1)
				(type default)
			)
			(layer "B.Fab")
		)
		(fp_line
			(start 0.12065 -0.2794)
			(end -0.12065 -0.2794)
			(stroke
				(width 0.1)
				(type default)
			)
			(layer "B.Fab")
		)
		(fp_line
			(start 0.12065 -0.305054)
			(end 0.12065 -0.2794)
			(stroke
				(width 0.1)
				(type default)
			)
			(layer "B.Fab")
		)
		(fp_line
			(start -0.120396 0.3048)
			(end -0.120396 0.2794)
			(stroke
				(width 0.1)
				(type default)
			)
			(layer "B.Fab")
		)
		(fp_line
			(start -0.120396 0.2794)
			(end 0.12065 0.2794)
			(stroke
				(width 0.1)
				(type default)
			)
			(layer "B.Fab")
		)
		(fp_line
			(start -0.12065 -0.2794)
			(end -0.12065 -0.3048)
			(stroke
				(width 0.1)
				(type default)
			)
			(layer "B.Fab")
		)
		(fp_line
			(start -0.12065 -0.3048)
			(end -0.67945 -0.3048)
			(stroke
				(width 0.1)
				(type default)
			)
			(layer "B.Fab")
		)
		(fp_line
			(start -0.67945 0.3048)
			(end -0.120396 0.3048)
			(stroke
				(width 0.1)
				(type default)
			)
			(layer "B.Fab")
		)
		(fp_line
			(start -0.67945 -0.3048)
			(end -0.67945 0.3048)
			(stroke
				(width 0.1)
				(type default)
			)
			(layer "B.Fab")
		)
		(pad "1" smd circle
			(at 0.40005 0)
			(size 0 0)
			(layers "B.Cu" "B.Mask" "B.Paste")
			(net "P1V8_CPU1_RT_1D_ADC")
		)
		(pad "2" smd circle
			(at -0.40005 0)
			(size 0 0)
			(layers "B.Cu" "B.Mask" "B.Paste")
			(net "GND")
		)
	)
	(footprint ""
		(layer "B.Cu")
		(at 361.046014 -259.845048 180)
		(property "Reference" "C2160"
			(at 0 0 0)
			(layer "B.SilkS")
			(hide yes)
			(effects
				(font
					(size 1.27 1.27)
				)
				(justify mirror)
			)
		)
		(property "Value" ""
			(at 0 0 0)
			(layer "B.Fab")
			(effects
				(font
					(size 1.27 1.27)
				)
				(justify mirror)
			)
		)
		(duplicate_pad_numbers_are_jumpers no)
		(fp_line
			(start 0.7874 0.4064)
			(end 0.7874 -0.4064)
			(stroke
				(width 0.1524)
				(type default)
			)
			(layer "B.SilkS")
		)
		(fp_line
			(start 0.7874 -0.4064)
			(end -0.7874 -0.4064)
			(stroke
				(width 0.1524)
				(type default)
			)
			(layer "B.SilkS")
		)
		(fp_line
			(start -0.7874 0.4064)
			(end 0.7874 0.4064)
			(stroke
				(width 0.1524)
				(type default)
			)
			(layer "B.SilkS")
		)
		(fp_line
			(start -0.7874 -0.4064)
			(end -0.7874 0.4064)
			(stroke
				(width 0.1524)
				(type default)
			)
			(layer "B.SilkS")
		)
		(fp_line
			(start 0.67945 0.3048)
			(end 0.67945 -0.305054)
			(stroke
				(width 0.1)
				(type default)
			)
			(layer "B.Fab")
		)
		(fp_line
			(start 0.67945 -0.305054)
			(end 0.12065 -0.305054)
			(stroke
				(width 0.1)
				(type default)
			)
			(layer "B.Fab")
		)
		(fp_line
			(start 0.12065 0.3048)
			(end 0.67945 0.3048)
			(stroke
				(width 0.1)
				(type default)
			)
			(layer "B.Fab")
		)
		(fp_line
			(start 0.12065 0.2794)
			(end 0.12065 0.3048)
			(stroke
				(width 0.1)
				(type default)
			)
			(layer "B.Fab")
		)
		(fp_line
			(start 0.12065 -0.2794)
			(end -0.12065 -0.2794)
			(stroke
				(width 0.1)
				(type default)
			)
			(layer "B.Fab")
		)
		(fp_line
			(start 0.12065 -0.305054)
			(end 0.12065 -0.2794)
			(stroke
				(width 0.1)
				(type default)
			)
			(layer "B.Fab")
		)
		(fp_line
			(start -0.120396 0.3048)
			(end -0.120396 0.2794)
			(stroke
				(width 0.1)
				(type default)
			)
			(layer "B.Fab")
		)
		(fp_line
			(start -0.120396 0.2794)
			(end 0.12065 0.2794)
			(stroke
				(width 0.1)
				(type default)
			)
			(layer "B.Fab")
		)
		(fp_line
			(start -0.12065 -0.2794)
			(end -0.12065 -0.3048)
			(stroke
				(width 0.1)
				(type default)
			)
			(layer "B.Fab")
		)
		(fp_line
			(start -0.12065 -0.3048)
			(end -0.67945 -0.3048)
			(stroke
				(width 0.1)
				(type default)
			)
			(layer "B.Fab")
		)
		(fp_line
			(start -0.67945 0.3048)
			(end -0.120396 0.3048)
			(stroke
				(width 0.1)
				(type default)
			)
			(layer "B.Fab")
		)
		(fp_line
			(start -0.67945 -0.3048)
			(end -0.67945 0.3048)
			(stroke
				(width 0.1)
				(type default)
			)
			(layer "B.Fab")
		)
		(pad "1" smd circle
			(at 0.40005 0)
			(size 0 0)
			(layers "B.Cu" "B.Mask" "B.Paste")
			(net "PVDD11_S3_P0")
		)
		(pad "2" smd circle
			(at -0.40005 0)
			(size 0 0)
			(layers "B.Cu" "B.Mask" "B.Paste")
			(net "GND")
		)
	)
)
